(kicad_pcb
	(version 20260206)
	(generator "pcbnew")
	(generator_version "10.0")
	(general
		(thickness 1.6)
		(legacy_teardrops no)
	)
	(paper "A4")
	(title_block
		(title "01162023_DA0F0TEBIF0_F0T_Expander_BD_F_brd_V02_OCP.brd")
		(comment 1 "Grand Teton / footprint 4451 of 9728 (PEX3), pads 595-713 of 2397")
	)
	(layers
		(0 "F.Cu" signal "TOP")
		(4 "In1.Cu" signal "GND")
		(6 "In2.Cu" signal "VCC")
		(8 "In3.Cu" signal "VCC1")
		(10 "In4.Cu" signal "GND1")
		(12 "In5.Cu" signal "IN1")
		(14 "In6.Cu" signal "GND2")
		(16 "In7.Cu" signal "IN2")
		(18 "In8.Cu" signal "GND3")
		(20 "In9.Cu" signal "IN3")
		(22 "In10.Cu" signal "GND4")
		(24 "In11.Cu" signal "IN4")
		(26 "In12.Cu" signal "GND5")
		(28 "In13.Cu" signal "IN5")
		(30 "In14.Cu" signal "GND6")
		(32 "In15.Cu" signal "IN6")
		(34 "In16.Cu" signal "GND7")
		(2 "B.Cu" signal "BOTTOM")
		(9 "F.Adhes" user "F.Adhesive")
		(11 "B.Adhes" user "B.Adhesive")
		(13 "F.Paste" user "Package Geometry/Pastemask Top")
		(15 "B.Paste" user "Package Geometry/Pastemask Bottom")
		(5 "F.SilkS" user "Ref Des/Silkscreen Top")
		(7 "B.SilkS" user "Ref Des/Silkscreen Bottom")
		(1 "F.Mask" user "Board Geometry/Soldermask Top")
		(3 "B.Mask" user "Board Geometry/Soldermask Bottom")
		(17 "Dwgs.User" user "User.Drawings")
		(19 "Cmts.User" user "User.Comments")
		(21 "Eco1.User" user "User.Eco1")
		(23 "Eco2.User" user "User.Eco2")
		(25 "Edge.Cuts" user "Board Geometry/Outline")
		(27 "Margin" user)
		(31 "F.CrtYd" user "Package Geometry/Place Bound Top")
		(29 "B.CrtYd" user "Package Geometry/Place Bound Bottom")
		(35 "F.Fab" user "Ref Des/Assembly Top")
		(33 "B.Fab" user "Ref Des/Assembly Bottom")
	)
	(footprint ""
		(layer "F.Cu")
		(at 407.949908 -295.89984)
		(property "Reference" "PEX3"
			(at -3.358642 35.5727 0)
			(unlocked yes)
			(layer "F.SilkS")
			(effects
				(font
					(size 2.032 1.524)
					(thickness 0.1524)
				)
				(justify left)
			)
		)
		(property "Value" ""
			(at 0 0 0)
			(layer "F.Fab")
			(effects
				(font
					(size 1.27 1.27)
				)
			)
		)
		(duplicate_pad_numbers_are_jumpers no)
		(pad "AM9" smd circle
			(at -15.200122 6.649974)
			(size 0.4572 0.4572)
			(layers "F.Cu" "F.Mask" "F.Paste")
			(net "Net_1437")
		)
		(pad "AM10" smd circle
			(at -14.249908 6.649974)
			(size 0.4572 0.4572)
			(layers "F.Cu" "F.Mask" "F.Paste")
			(net "GND")
		)
		(pad "AM11" smd circle
			(at -13.299948 6.649974)
			(size 0.4572 0.4572)
			(layers "F.Cu" "F.Mask" "F.Paste")
			(net "GND")
		)
		(pad "AM12" smd circle
			(at -12.349988 6.649974)
			(size 0.4572 0.4572)
			(layers "F.Cu" "F.Mask" "F.Paste")
			(net "TP_PEX3_VDDQ_EFUSE")
		)
		(pad "AM13" smd circle
			(at -11.400028 6.649974)
			(size 0.4572 0.4572)
			(layers "F.Cu" "F.Mask" "F.Paste")
			(net "GND")
		)
		(pad "AM14" smd circle
			(at -10.450068 6.649974)
			(size 0.4572 0.4572)
			(layers "F.Cu" "F.Mask" "F.Paste")
			(net "P1V8_VDDA_PEX3")
		)
		(pad "AM15" smd circle
			(at -9.500108 6.649974)
			(size 0.4572 0.4572)
			(layers "F.Cu" "F.Mask" "F.Paste")
			(net "GND")
		)
		(pad "AM16" smd circle
			(at -8.549894 6.649974)
			(size 0.4572 0.4572)
			(layers "F.Cu" "F.Mask" "F.Paste")
			(net "P1V25_PEX3")
		)
		(pad "AM17" smd circle
			(at -7.599934 6.649974)
			(size 0.4572 0.4572)
			(layers "F.Cu" "F.Mask" "F.Paste")
			(net "P1V25_PEX3")
		)
		(pad "AM18" smd circle
			(at -6.649974 6.649974)
			(size 0.4572 0.4572)
			(layers "F.Cu" "F.Mask" "F.Paste")
			(net "P1V25_PEX3")
		)
		(pad "AM19" smd circle
			(at -5.700014 6.649974)
			(size 0.4572 0.4572)
			(layers "F.Cu" "F.Mask" "F.Paste")
			(net "P1V25_PEX3")
		)
		(pad "AM20" smd circle
			(at -4.750054 6.649974)
			(size 0.4572 0.4572)
			(layers "F.Cu" "F.Mask" "F.Paste")
			(net "P1V25_PEX3")
		)
		(pad "AM21" smd circle
			(at -3.800094 6.649974)
			(size 0.4572 0.4572)
			(layers "F.Cu" "F.Mask" "F.Paste")
			(net "P1V25_PEX3")
		)
		(pad "AM22" smd circle
			(at -2.84988 6.649974)
			(size 0.4572 0.4572)
			(layers "F.Cu" "F.Mask" "F.Paste")
			(net "P1V25_PEX3")
		)
		(pad "AM23" smd circle
			(at -1.89992 6.649974)
			(size 0.4572 0.4572)
			(layers "F.Cu" "F.Mask" "F.Paste")
			(net "P1V25_PEX3")
		)
		(pad "AM24" smd circle
			(at -0.94996 6.649974)
			(size 0.4572 0.4572)
			(layers "F.Cu" "F.Mask" "F.Paste")
			(net "P1V25_PEX3")
		)
		(pad "AM25" smd circle
			(at 0 6.649974)
			(size 0.4572 0.4572)
			(layers "F.Cu" "F.Mask" "F.Paste")
			(net "P1V25_PEX3")
		)
		(pad "AM26" smd circle
			(at 0.94996 6.649974)
			(size 0.4572 0.4572)
			(layers "F.Cu" "F.Mask" "F.Paste")
			(net "P1V25_PEX3")
		)
		(pad "AM27" smd circle
			(at 1.89992 6.649974)
			(size 0.4572 0.4572)
			(layers "F.Cu" "F.Mask" "F.Paste")
			(net "P1V25_PEX3")
		)
		(pad "AM28" smd circle
			(at 2.84988 6.649974)
			(size 0.4572 0.4572)
			(layers "F.Cu" "F.Mask" "F.Paste")
			(net "P1V25_PEX3")
		)
		(pad "AM29" smd circle
			(at 3.800094 6.649974)
			(size 0.4572 0.4572)
			(layers "F.Cu" "F.Mask" "F.Paste")
			(net "P1V25_PEX3")
		)
		(pad "AM30" smd circle
			(at 4.750054 6.649974)
			(size 0.4572 0.4572)
			(layers "F.Cu" "F.Mask" "F.Paste")
			(net "P1V25_PEX3")
		)
		(pad "AM31" smd circle
			(at 5.700014 6.649974)
			(size 0.4572 0.4572)
			(layers "F.Cu" "F.Mask" "F.Paste")
			(net "P1V25_PEX3")
		)
		(pad "AM32" smd circle
			(at 6.649974 6.649974)
			(size 0.4572 0.4572)
			(layers "F.Cu" "F.Mask" "F.Paste")
			(net "P1V25_PEX3")
		)
		(pad "AM33" smd circle
			(at 7.599934 6.649974)
			(size 0.4572 0.4572)
			(layers "F.Cu" "F.Mask" "F.Paste")
			(net "P1V25_PEX3")
		)
		(pad "AM34" smd circle
			(at 8.549894 6.649974)
			(size 0.4572 0.4572)
			(layers "F.Cu" "F.Mask" "F.Paste")
			(net "GND")
		)
		(pad "AM35" smd circle
			(at 9.500108 6.649974)
			(size 0.4572 0.4572)
			(layers "F.Cu" "F.Mask" "F.Paste")
			(net "P1V8_PEX")
		)
		(pad "AM36" smd circle
			(at 10.450068 6.649974)
			(size 0.4572 0.4572)
			(layers "F.Cu" "F.Mask" "F.Paste")
			(net "GND")
		)
		(pad "AM37" smd circle
			(at 11.400028 6.649974)
			(size 0.4572 0.4572)
			(layers "F.Cu" "F.Mask" "F.Paste")
			(net "GND")
		)
		(pad "AM38" smd circle
			(at 12.349988 6.649974)
			(size 0.4572 0.4572)
			(layers "F.Cu" "F.Mask" "F.Paste")
			(net "Net_5416")
		)
		(pad "AM39" smd circle
			(at 13.299948 6.649974)
			(size 0.4572 0.4572)
			(layers "F.Cu" "F.Mask" "F.Paste")
			(net "Net_5459")
		)
		(pad "AM40" smd circle
			(at 14.249908 6.649974)
			(size 0.4572 0.4572)
			(layers "F.Cu" "F.Mask" "F.Paste")
			(net "GND")
		)
		(pad "AM41" smd circle
			(at 15.200122 6.649974)
			(size 0.4572 0.4572)
			(layers "F.Cu" "F.Mask" "F.Paste")
			(net "Net_1515")
		)
		(pad "AM42" smd circle
			(at 16.150082 6.649974)
			(size 0.4572 0.4572)
			(layers "F.Cu" "F.Mask" "F.Paste")
			(net "Net_1518")
		)
		(pad "AM43" smd circle
			(at 17.100042 6.649974)
			(size 0.4572 0.4572)
			(layers "F.Cu" "F.Mask" "F.Paste")
			(net "GND")
		)
		(pad "AM44" smd circle
			(at 18.050002 6.649974)
			(size 0.4572 0.4572)
			(layers "F.Cu" "F.Mask" "F.Paste")
			(net "GND")
		)
		(pad "AM45" smd circle
			(at 18.999962 6.649974)
			(size 0.4572 0.4572)
			(layers "F.Cu" "F.Mask" "F.Paste")
			(net "GND")
		)
		(pad "AM46" smd circle
			(at 19.949922 6.649974)
			(size 0.4572 0.4572)
			(layers "F.Cu" "F.Mask" "F.Paste")
			(net "GND")
		)
		(pad "AM47" smd circle
			(at 20.899882 6.649974)
			(size 0.4572 0.4572)
			(layers "F.Cu" "F.Mask" "F.Paste")
			(net "GND")
		)
		(pad "AM48" smd circle
			(at 21.850096 6.649974)
			(size 0.4572 0.4572)
			(layers "F.Cu" "F.Mask" "F.Paste")
			(net "Net_1510")
		)
		(pad "AM49" smd circle
			(at 22.800056 6.649974)
			(size 0.4572 0.4572)
			(layers "F.Cu" "F.Mask" "F.Paste")
			(net "Net_1461")
		)
		(pad "AN1" smd circle
			(at -22.800056 7.599934)
			(size 0.4572 0.4572)
			(layers "F.Cu" "F.Mask" "F.Paste")
			(net "GND")
		)
		(pad "AN2" smd circle
			(at -21.850096 7.599934)
			(size 0.4572 0.4572)
			(layers "F.Cu" "F.Mask" "F.Paste")
			(net "GND")
		)
		(pad "AN3" smd circle
			(at -20.899882 7.599934)
			(size 0.4572 0.4572)
			(layers "F.Cu" "F.Mask" "F.Paste")
			(net "Net_1441")
		)
		(pad "AN4" smd circle
			(at -19.949922 7.599934)
			(size 0.4572 0.4572)
			(layers "F.Cu" "F.Mask" "F.Paste")
			(net "Net_1460")
		)
		(pad "AN5" smd circle
			(at -18.999962 7.599934)
			(size 0.4572 0.4572)
			(layers "F.Cu" "F.Mask" "F.Paste")
			(net "GND")
		)
		(pad "AN6" smd circle
			(at -18.050002 7.599934)
			(size 0.4572 0.4572)
			(layers "F.Cu" "F.Mask" "F.Paste")
			(net "Net_1731")
		)
		(pad "AN7" smd circle
			(at -17.100042 7.599934)
			(size 0.4572 0.4572)
			(layers "F.Cu" "F.Mask" "F.Paste")
			(net "Net_1732")
		)
		(pad "AN8" smd circle
			(at -16.150082 7.599934)
			(size 0.4572 0.4572)
			(layers "F.Cu" "F.Mask" "F.Paste")
			(net "GND")
		)
		(pad "AN9" smd circle
			(at -15.200122 7.599934)
			(size 0.4572 0.4572)
			(layers "F.Cu" "F.Mask" "F.Paste")
			(net "GND")
		)
		(pad "AN10" smd circle
			(at -14.249908 7.599934)
			(size 0.4572 0.4572)
			(layers "F.Cu" "F.Mask" "F.Paste")
			(net "GND")
		)
		(pad "AN11" smd circle
			(at -13.299948 7.599934)
			(size 0.4572 0.4572)
			(layers "F.Cu" "F.Mask" "F.Paste")
			(net "GND")
		)
		(pad "AN12" smd circle
			(at -12.349988 7.599934)
			(size 0.4572 0.4572)
			(layers "F.Cu" "F.Mask" "F.Paste")
			(net "GND")
		)
		(pad "AN13" smd circle
			(at -11.400028 7.599934)
			(size 0.4572 0.4572)
			(layers "F.Cu" "F.Mask" "F.Paste")
			(net "GND")
		)
		(pad "AN14" smd circle
			(at -10.450068 7.599934)
			(size 0.4572 0.4572)
			(layers "F.Cu" "F.Mask" "F.Paste")
			(net "Net_527")
		)
		(pad "AN15" smd circle
			(at -9.500108 7.599934)
			(size 0.4572 0.4572)
			(layers "F.Cu" "F.Mask" "F.Paste")
			(net "GND")
		)
		(pad "AN16" smd circle
			(at -8.549894 7.599934)
			(size 0.4572 0.4572)
			(layers "F.Cu" "F.Mask" "F.Paste")
			(net "GND")
		)
		(pad "AN17" smd circle
			(at -7.599934 7.599934)
			(size 0.4572 0.4572)
			(layers "F.Cu" "F.Mask" "F.Paste")
			(net "GND")
		)
		(pad "AN18" smd circle
			(at -6.649974 7.599934)
			(size 0.4572 0.4572)
			(layers "F.Cu" "F.Mask" "F.Paste")
			(net "GND")
		)
		(pad "AN19" smd circle
			(at -5.700014 7.599934)
			(size 0.4572 0.4572)
			(layers "F.Cu" "F.Mask" "F.Paste")
			(net "GND")
		)
		(pad "AN20" smd circle
			(at -4.750054 7.599934)
			(size 0.4572 0.4572)
			(layers "F.Cu" "F.Mask" "F.Paste")
			(net "GND")
		)
		(pad "AN21" smd circle
			(at -3.800094 7.599934)
			(size 0.4572 0.4572)
			(layers "F.Cu" "F.Mask" "F.Paste")
			(net "GND")
		)
		(pad "AN22" smd circle
			(at -2.84988 7.599934)
			(size 0.4572 0.4572)
			(layers "F.Cu" "F.Mask" "F.Paste")
			(net "GND")
		)
		(pad "AN23" smd circle
			(at -1.89992 7.599934)
			(size 0.4572 0.4572)
			(layers "F.Cu" "F.Mask" "F.Paste")
			(net "GND")
		)
		(pad "AN24" smd circle
			(at -0.94996 7.599934)
			(size 0.4572 0.4572)
			(layers "F.Cu" "F.Mask" "F.Paste")
			(net "GND")
		)
		(pad "AN25" smd circle
			(at 0 7.599934)
			(size 0.4572 0.4572)
			(layers "F.Cu" "F.Mask" "F.Paste")
			(net "GND")
		)
		(pad "AN26" smd circle
			(at 0.94996 7.599934)
			(size 0.4572 0.4572)
			(layers "F.Cu" "F.Mask" "F.Paste")
			(net "GND")
		)
		(pad "AN27" smd circle
			(at 1.89992 7.599934)
			(size 0.4572 0.4572)
			(layers "F.Cu" "F.Mask" "F.Paste")
			(net "GND")
		)
		(pad "AN28" smd circle
			(at 2.84988 7.599934)
			(size 0.4572 0.4572)
			(layers "F.Cu" "F.Mask" "F.Paste")
			(net "GND")
		)
		(pad "AN29" smd circle
			(at 3.800094 7.599934)
			(size 0.4572 0.4572)
			(layers "F.Cu" "F.Mask" "F.Paste")
			(net "GND")
		)
		(pad "AN30" smd circle
			(at 4.750054 7.599934)
			(size 0.4572 0.4572)
			(layers "F.Cu" "F.Mask" "F.Paste")
			(net "GND")
		)
		(pad "AN31" smd circle
			(at 5.700014 7.599934)
			(size 0.4572 0.4572)
			(layers "F.Cu" "F.Mask" "F.Paste")
			(net "GND")
		)
		(pad "AN32" smd circle
			(at 6.649974 7.599934)
			(size 0.4572 0.4572)
			(layers "F.Cu" "F.Mask" "F.Paste")
			(net "GND")
		)
		(pad "AN33" smd circle
			(at 7.599934 7.599934)
			(size 0.4572 0.4572)
			(layers "F.Cu" "F.Mask" "F.Paste")
			(net "GND")
		)
		(pad "AN34" smd circle
			(at 8.549894 7.599934)
			(size 0.4572 0.4572)
			(layers "F.Cu" "F.Mask" "F.Paste")
			(net "GND")
		)
		(pad "AN35" smd circle
			(at 9.500108 7.599934)
			(size 0.4572 0.4572)
			(layers "F.Cu" "F.Mask" "F.Paste")
			(net "GND")
		)
		(pad "AN36" smd circle
			(at 10.450068 7.599934)
			(size 0.4572 0.4572)
			(layers "F.Cu" "F.Mask" "F.Paste")
			(net "Net_540")
		)
		(pad "AN37" smd circle
			(at 11.400028 7.599934)
			(size 0.4572 0.4572)
			(layers "F.Cu" "F.Mask" "F.Paste")
			(net "GND")
		)
		(pad "AN38" smd circle
			(at 12.349988 7.599934)
			(size 0.4572 0.4572)
			(layers "F.Cu" "F.Mask" "F.Paste")
			(net "Net_5450")
		)
		(pad "AN39" smd circle
			(at 13.299948 7.599934)
			(size 0.4572 0.4572)
			(layers "F.Cu" "F.Mask" "F.Paste")
			(net "Net_5417")
		)
		(pad "AN40" smd circle
			(at 14.249908 7.599934)
			(size 0.4572 0.4572)
			(layers "F.Cu" "F.Mask" "F.Paste")
			(net "GND")
		)
		(pad "AN41" smd circle
			(at 15.200122 7.599934)
			(size 0.4572 0.4572)
			(layers "F.Cu" "F.Mask" "F.Paste")
			(net "GND")
		)
		(pad "AN42" smd circle
			(at 16.150082 7.599934)
			(size 0.4572 0.4572)
			(layers "F.Cu" "F.Mask" "F.Paste")
			(net "GND")
		)
		(pad "AN43" smd circle
			(at 17.100042 7.599934)
			(size 0.4572 0.4572)
			(layers "F.Cu" "F.Mask" "F.Paste")
			(net "P5E_PEX3_STN0_TX_DP<0>")
		)
		(pad "AN44" smd circle
			(at 18.050002 7.599934)
			(size 0.4572 0.4572)
			(layers "F.Cu" "F.Mask" "F.Paste")
			(net "P5E_PEX3_STN0_TX_DN<0>")
		)
		(pad "AN45" smd circle
			(at 18.999962 7.599934)
			(size 0.4572 0.4572)
			(layers "F.Cu" "F.Mask" "F.Paste")
			(net "GND")
		)
		(pad "AN46" smd circle
			(at 19.949922 7.599934)
			(size 0.4572 0.4572)
			(layers "F.Cu" "F.Mask" "F.Paste")
			(net "P5E_PEX3_STN0_RX_DP<0>")
		)
		(pad "AN47" smd circle
			(at 20.899882 7.599934)
			(size 0.4572 0.4572)
			(layers "F.Cu" "F.Mask" "F.Paste")
			(net "P5E_PEX3_STN0_RX_DN<0>")
		)
		(pad "AN48" smd circle
			(at 21.850096 7.599934)
			(size 0.4572 0.4572)
			(layers "F.Cu" "F.Mask" "F.Paste")
			(net "GND")
		)
		(pad "AN49" smd circle
			(at 22.800056 7.599934)
			(size 0.4572 0.4572)
			(layers "F.Cu" "F.Mask" "F.Paste")
			(net "GND")
		)
		(pad "AP1" smd circle
			(at -22.800056 8.549894)
			(size 0.4572 0.4572)
			(layers "F.Cu" "F.Mask" "F.Paste")
			(net "Net_1472")
		)
		(pad "AP2" smd circle
			(at -21.850096 8.549894)
			(size 0.4572 0.4572)
			(layers "F.Cu" "F.Mask" "F.Paste")
			(net "Net_1493")
		)
		(pad "AP3" smd circle
			(at -20.899882 8.549894)
			(size 0.4572 0.4572)
			(layers "F.Cu" "F.Mask" "F.Paste")
			(net "GND")
		)
		(pad "AP4" smd circle
			(at -19.949922 8.549894)
			(size 0.4572 0.4572)
			(layers "F.Cu" "F.Mask" "F.Paste")
			(net "GND")
		)
		(pad "AP5" smd circle
			(at -18.999962 8.549894)
			(size 0.4572 0.4572)
			(layers "F.Cu" "F.Mask" "F.Paste")
			(net "GND")
		)
		(pad "AP6" smd circle
			(at -18.050002 8.549894)
			(size 0.4572 0.4572)
			(layers "F.Cu" "F.Mask" "F.Paste")
			(net "GND")
		)
		(pad "AP7" smd circle
			(at -17.100042 8.549894)
			(size 0.4572 0.4572)
			(layers "F.Cu" "F.Mask" "F.Paste")
			(net "GND")
		)
		(pad "AP8" smd circle
			(at -16.150082 8.549894)
			(size 0.4572 0.4572)
			(layers "F.Cu" "F.Mask" "F.Paste")
			(net "Net_1463")
		)
		(pad "AP9" smd circle
			(at -15.200122 8.549894)
			(size 0.4572 0.4572)
			(layers "F.Cu" "F.Mask" "F.Paste")
			(net "Net_1474")
		)
		(pad "AP10" smd circle
			(at -14.249908 8.549894)
			(size 0.4572 0.4572)
			(layers "F.Cu" "F.Mask" "F.Paste")
			(net "GND")
		)
		(pad "AP11" smd circle
			(at -13.299948 8.549894)
			(size 0.4572 0.4572)
			(layers "F.Cu" "F.Mask" "F.Paste")
			(net "GND")
		)
		(pad "AP12" smd circle
			(at -12.349988 8.549894)
			(size 0.4572 0.4572)
			(layers "F.Cu" "F.Mask" "F.Paste")
			(net "GND")
		)
		(pad "AP13" smd circle
			(at -11.400028 8.549894)
			(size 0.4572 0.4572)
			(layers "F.Cu" "F.Mask" "F.Paste")
			(net "GND")
		)
		(pad "AP14" smd circle
			(at -10.450068 8.549894)
			(size 0.4572 0.4572)
			(layers "F.Cu" "F.Mask" "F.Paste")
			(net "Net_530")
		)
		(pad "AP15" smd circle
			(at -9.500108 8.549894)
			(size 0.4572 0.4572)
			(layers "F.Cu" "F.Mask" "F.Paste")
			(net "GND")
		)
		(pad "AP16" smd circle
			(at -8.549894 8.549894)
			(size 0.4572 0.4572)
			(layers "F.Cu" "F.Mask" "F.Paste")
			(net "P1V25_SERDES_VDDPLL_PEX3")
		)
		(pad "AP17" smd circle
			(at -7.599934 8.549894)
			(size 0.4572 0.4572)
			(layers "F.Cu" "F.Mask" "F.Paste")
			(net "P1V25_SERDES_VDDPLL_PEX3")
		)
		(pad "AP18" smd circle
			(at -6.649974 8.549894)
			(size 0.4572 0.4572)
			(layers "F.Cu" "F.Mask" "F.Paste")
			(net "P1V25_SERDES_VDDPLL_PEX3")
		)
		(pad "AP19" smd circle
			(at -5.700014 8.549894)
			(size 0.4572 0.4572)
			(layers "F.Cu" "F.Mask" "F.Paste")
			(net "P1V25_SERDES_VDDPLL_PEX3")
		)
		(pad "AP20" smd circle
			(at -4.750054 8.549894)
			(size 0.4572 0.4572)
			(layers "F.Cu" "F.Mask" "F.Paste")
			(net "P1V25_SERDES_VDDPLL_PEX3")
		)
		(pad "AP21" smd circle
			(at -3.800094 8.549894)
			(size 0.4572 0.4572)
			(layers "F.Cu" "F.Mask" "F.Paste")
			(net "P1V25_SERDES_VDDPLL_PEX3")
		)
		(pad "AP22" smd circle
			(at -2.84988 8.549894)
			(size 0.4572 0.4572)
			(layers "F.Cu" "F.Mask" "F.Paste")
			(net "P1V25_SERDES_VDDPLL_PEX3")
		)
		(pad "AP23" smd circle
			(at -1.89992 8.549894)
			(size 0.4572 0.4572)
			(layers "F.Cu" "F.Mask" "F.Paste")
			(net "P1V25_SERDES_VDDPLL_PEX3")
		)
		(pad "AP24" smd circle
			(at -0.94996 8.549894)
			(size 0.4572 0.4572)
			(layers "F.Cu" "F.Mask" "F.Paste")
			(net "P1V25_SERDES_VDDPLL_PEX3")
		)
		(pad "AP25" smd circle
			(at 0 8.549894)
			(size 0.4572 0.4572)
			(layers "F.Cu" "F.Mask" "F.Paste")
			(net "P1V25_SERDES_VDDPLL_PEX3")
		)
		(pad "AP26" smd circle
			(at 0.94996 8.549894)
			(size 0.4572 0.4572)
			(layers "F.Cu" "F.Mask" "F.Paste")
			(net "P1V25_SERDES_VDDPLL_PEX3")
		)
		(pad "AP27" smd circle
			(at 1.89992 8.549894)
			(size 0.4572 0.4572)
			(layers "F.Cu" "F.Mask" "F.Paste")
			(net "P1V25_SERDES_VDDPLL_PEX3")
		)
		(pad "AP28" smd circle
			(at 2.84988 8.549894)
			(size 0.4572 0.4572)
			(layers "F.Cu" "F.Mask" "F.Paste")
			(net "P1V25_SERDES_VDDPLL_PEX3")
		)
		(pad "AP29" smd circle
			(at 3.800094 8.549894)
			(size 0.4572 0.4572)
			(layers "F.Cu" "F.Mask" "F.Paste")
			(net "P1V25_SERDES_VDDPLL_PEX3")
		)
	)
)
